(kicad_pcb
	(version 20221018)
	(generator pcbnew)
	(general
    (thickness 1.518)
  )
	(paper "A4")
	(title_block
    (title "Kria K26 Devboard")
    (date "2024-03-26")
    (rev "1.2.5")
    (comment 1 "www.antmicro.com")
    (comment 2 "Antmicro Ltd.")
		(comment 9 "footprints 218-226 of 660")
	)
	(layers
    (0 "F.Cu" mixed)
    (1 "In1.Cu" power)
    (2 "In2.Cu" mixed)
    (3 "In3.Cu" power)
    (4 "In4.Cu" mixed)
    (5 "In5.Cu" power)
    (6 "In6.Cu" mixed)
    (31 "B.Cu" power)
    (32 "B.Adhes" user "B.Adhesive")
    (33 "F.Adhes" user "F.Adhesive")
    (34 "B.Paste" user)
    (35 "F.Paste" user)
    (36 "B.SilkS" user "B.Silkscreen")
    (37 "F.SilkS" user "F.Silkscreen")
    (38 "B.Mask" user)
    (39 "F.Mask" user)
    (40 "Dwgs.User" user "User.Drawings")
    (41 "Cmts.User" user "User.Comments")
    (42 "Eco1.User" user "User.Eco1")
    (43 "Eco2.User" user "User.Eco2")
    (44 "Edge.Cuts" user)
    (45 "Margin" user)
    (46 "B.CrtYd" user "B.Courtyard")
    (47 "F.CrtYd" user "F.Courtyard")
    (48 "B.Fab" user)
    (49 "F.Fab" user)
  )
	(footprint "kria-k26-devboard-footprints:TP_SMD_0.75mm" (layer "F.Cu")
    (at 134.725 116.85)
    (property "Author" "Antmicro")
    (property "License" "Apache-2.0")
    (property "MPN" "")
    (property "Manufacturer" "")
    (property "Sheetfile" "pcie-m2-key-e.kicad_sch")
    (property "Sheetname" "PCIE M2 key E ")
    (property "ki_description" "Test Point 0.75mm")
    (attr exclude_from_pos_files)
    (fp_text reference "TP48" (at -1.335 -0.33) (layer "F.SilkS")
        (effects (font (size 0.7 0.7) (thickness 0.15)) (justify left bottom))
    )
    (fp_text value "TP_0.75mm_SMD" (at 0 1.2) (layer "F.Fab") hide
        (effects (font (size 0.7 0.7) (thickness 0.15)) (justify left bottom))
    )
    (fp_text user "Author: Antmicro" (at -0.4 3.901) (layer "F.Fab") hide
        (effects (font (size 0.7 0.7) (thickness 0.15)) (justify left bottom))
    )
    (fp_text user "${REFERENCE}" (at -0.4 2.7) (layer "F.Fab") hide
        (effects (font (size 0.7 0.7) (thickness 0.15)) (justify left bottom))
    )
    (fp_text user "License: Apache-2.0" (at -0.4 5.101) (layer "F.Fab") hide
        (effects (font (size 0.7 0.7) (thickness 0.15)) (justify left bottom))
    )
    (pad "1" smd circle (at 0 0) (size 0.75 0.75) (layers "F.Cu" "F.Mask")
      (net 227 "/PCIE M2 key E /~{M2_PEWAKE}") (pinfunction "1") (pintype "passive"))
  )
	(footprint "kria-k26-devboard-footprints:TP_SMD_0.75mm" (layer "F.Cu")
    (at 126 117.625)
    (property "Author" "Antmicro")
    (property "License" "Apache-2.0")
    (property "MPN" "")
    (property "Manufacturer" "")
    (property "Sheetfile" "pcie-m2-key-e.kicad_sch")
    (property "Sheetname" "PCIE M2 key E ")
    (property "ki_description" "Test Point 0.75mm")
    (attr exclude_from_pos_files)
    (fp_text reference "TP49" (at -1.35 -0.375) (layer "F.SilkS")
        (effects (font (size 0.7 0.7) (thickness 0.15)) (justify left bottom))
    )
    (fp_text value "TP_0.75mm_SMD" (at 0 1.2) (layer "F.Fab") hide
        (effects (font (size 0.7 0.7) (thickness 0.15)) (justify left bottom))
    )
    (fp_text user "Author: Antmicro" (at -0.4 3.901) (layer "F.Fab") hide
        (effects (font (size 0.7 0.7) (thickness 0.15)) (justify left bottom))
    )
    (fp_text user "License: Apache-2.0" (at -0.4 5.101) (layer "F.Fab") hide
        (effects (font (size 0.7 0.7) (thickness 0.15)) (justify left bottom))
    )
    (fp_text user "${REFERENCE}" (at -0.4 2.7) (layer "F.Fab") hide
        (effects (font (size 0.7 0.7) (thickness 0.15)) (justify left bottom))
    )
    (pad "1" smd circle (at 0 0) (size 0.75 0.75) (layers "F.Cu" "F.Mask")
      (net 221 "/PCIE M2 key E /~{M2_PERST}") (pinfunction "1") (pintype "passive"))
  )
	(footprint "kria-k26-devboard-footprints:R_0402_1005Metric" (layer "F.Cu")
    (at 81.325 119.25 -90)
    (descr "Resistor SMD 0402")
    (tags "resistor SMD 0402")
    (property "Author" "Antmicro")
    (property "DNP" "DNP")
    (property "License" "Apache-2.0")
    (property "MPN" "CR0402-FX-1501GLF")
    (property "Manufacturer" "Bourns")
    (property "Sheetfile" "camera.kicad_sch")
    (property "Sheetname" "Camera interface")
    (property "Tolerance" "1%")
    (property "Val" "1k5")
    (property "dnp" "")
    (property "exclude_from_bom" "")
    (property "ki_description" "1k5 resistor in 0402 package with 1% tolerance")
    (attr exclude_from_pos_files exclude_from_bom)
    (fp_text reference "R28" (at -0.85 -0.355 -90) (layer "F.SilkS")
        (effects (font (size 0.7 0.7) (thickness 0.15)) (justify left bottom))
    )
    (fp_text value "R_1k5_0402" (at 0 1.4 -90) (layer "F.Fab") hide
        (effects (font (size 0.7 0.7) (thickness 0.15)) (justify left bottom))
    )
    (fp_text user "Author: Antmicro" (at -0.95 4.169 -90) (layer "F.Fab") hide
        (effects (font (size 0.7 0.7) (thickness 0.15)) (justify left bottom))
    )
    (fp_text user "${REFERENCE}" (at -0.95 3.168 -90) (layer "F.Fab") hide
        (effects (font (size 0.7 0.7) (thickness 0.15)) (justify left bottom))
    )
    (fp_text user "License: Apache-2.0" (at -0.95 5.169 -90) (layer "F.Fab") hide
        (effects (font (size 0.7 0.7) (thickness 0.15)) (justify left bottom))
    )
    (fp_rect (start -0.93 -0.47) (end 0.93 0.47)
      (stroke (width 0.05) (type solid)) (fill none) (layer "F.CrtYd"))
    (fp_rect (start -0.5 -0.25) (end 0.5 0.25)
      (stroke (width 0.15) (type solid)) (fill none) (layer "F.Fab"))
    (pad "1" smd roundrect (at -0.485 0 270) (size 0.59 0.64) (layers "F.Cu" "F.Paste" "F.Mask") (roundrect_rratio 0.25)
      (net 322 "PL_1V8") (pintype "passive"))
    (pad "2" smd roundrect (at 0.485 0 270) (size 0.59 0.64) (layers "F.Cu" "F.Paste" "F.Mask") (roundrect_rratio 0.25)
      (net 196 "/Camera interface/CCI0_I2C_SDA_3V3") (pintype "passive"))
  )
	(footprint "kria-k26-devboard-footprints:Oscillator_SMD_Abracon_AX3_3.2x2.5x1mm" (layer "F.Cu")
    (at 101.325 95.775 -90)
    (property "Author" "Antmicro")
    (property "License" "Apache-2.0")
    (property "MPN" "AX3DAF1-125.0000")
    (property "Manufacturer" "Abracon")
    (property "Sheetfile" "clock.kicad_sch")
    (property "Sheetname" "Clock distribution")
    (property "Val" "125 MHz")
    (property "ki_description" "125 MHz XO (Standard) LVDS Oscillator 3.3V Enable/Disable 6-SMD, No Lead")
    (property "ki_keywords" "OSCILLATOR, LVDS")
    (attr smd)
    (fp_text reference "Y3" (at 0.705 1.975 90) (layer "F.SilkS")
        (effects (font (size 0.7 0.7) (thickness 0.15)) (justify left bottom))
    )
    (fp_text value "Oscillator_125MHz_AX3DA" (at 0 2.8 90) (layer "F.Fab") hide
        (effects (font (size 0.7 0.7) (thickness 0.15)) (justify right bottom))
    )
    (fp_text user "Author: Antmicro" (at -1.6 5.3 90) (layer "F.Fab") hide
        (effects (font (size 0.7 0.7) (thickness 0.15)) (justify right bottom))
    )
    (fp_text user "License: Apache-2.0" (at -1.6 6.499 90) (layer "F.Fab") hide
        (effects (font (size 0.7 0.7) (thickness 0.15)) (justify right bottom))
    )
    (fp_text user "${REFERENCE}" (at -1.6 4.1 90) (layer "F.Fab") hide
        (effects (font (size 0.7 0.7) (thickness 0.15)) (justify right bottom))
    )
    (fp_line (start -1.5 -1.8) (end -1.5 -1.5)
      (stroke (width 0.12) (type solid)) (layer "F.SilkS"))
    (fp_line (start -1.5 1.5) (end -1.5 1.8)
      (stroke (width 0.12) (type solid)) (layer "F.SilkS"))
    (fp_line (start -1.5 1.8) (end 1.5 1.8)
      (stroke (width 0.12) (type solid)) (layer "F.SilkS"))
    (fp_line (start 1.5 -1.8) (end -1.5 -1.8)
      (stroke (width 0.12) (type solid)) (layer "F.SilkS"))
    (fp_line (start 1.5 -1.5) (end 1.5 -1.8)
      (stroke (width 0.12) (type solid)) (layer "F.SilkS"))
    (fp_line (start 1.5 1.8) (end 1.5 1.5)
      (stroke (width 0.12) (type solid)) (layer "F.SilkS"))
    (fp_circle (center -1.7 -1.9) (end -1.7 -1.85)
      (stroke (width 0.15) (type solid)) (fill solid) (layer "F.SilkS"))
    (fp_rect (start 1.6 -1.9) (end -1.6 1.9)
      (stroke (width 0.05) (type solid)) (fill none) (layer "F.CrtYd"))
    (fp_line (start -0.6 -1.6) (end -1.3 -0.9)
      (stroke (width 0.15) (type solid)) (layer "F.Fab"))
    (fp_rect (start 1.3 -1.601) (end -1.3 1.599)
      (stroke (width 0.15) (type solid)) (fill none) (layer "F.Fab"))
    (pad "1" smd rect (at -0.8 -1.199 180) (size 0.9 1.1) (layers "F.Cu" "F.Paste" "F.Mask")
      (net 185 "/Clock distribution/PS_CLK_EN") (pinfunction "EN") (pintype "input"))
    (pad "2" smd rect (at -0.8 0 180) (size 0.9 1.1) (layers "F.Cu" "F.Paste" "F.Mask")
      (net 797 "unconnected-(Y3-NC-Pad2)") (pinfunction "NC") (pintype "no_connect"))
    (pad "3" smd rect (at -0.8 1.199 180) (size 0.9 1.1) (layers "F.Cu" "F.Paste" "F.Mask")
      (net 1 "GND") (pinfunction "GND") (pintype "power_in"))
    (pad "4" smd rect (at 0.801 1.199 180) (size 0.9 1.1) (layers "F.Cu" "F.Paste" "F.Mask")
      (net 183 "/Clock distribution/GTR_REFCLK2_C2M_P") (pinfunction "OUT+") (pintype "output"))
    (pad "5" smd rect (at 0.801 0 180) (size 0.9 1.1) (layers "F.Cu" "F.Paste" "F.Mask")
      (net 184 "/Clock distribution/GTR_REFCLK2_C2M_N") (pinfunction "OUT-") (pintype "output"))
    (pad "6" smd rect (at 0.801 -1.199 180) (size 0.9 1.1) (layers "F.Cu" "F.Paste" "F.Mask")
      (net 15 "PS_3V3") (pinfunction "VCC") (pintype "power_in"))
  )
	(footprint "kria-k26-devboard-footprints:C_0402_1005Metric" (layer "F.Cu")
    (at 103.7 96.199999 90)
    (descr "Capacitor SMD 0402")
    (tags "capacitor SMD 0402")
    (property "Author" "Antmicro")
    (property "Dielectric" "X5R")
    (property "License" "Apache-2.0")
    (property "MPN" "GRM155R61H104KE14D")
    (property "Manufacturer" "Murata")
    (property "Sheetfile" "clock.kicad_sch")
    (property "Sheetname" "Clock distribution")
    (property "Val" "100n")
    (property "Voltage" "50V")
    (property "ki_description" " ")
    (attr smd)
    (fp_text reference "C28" (at 0.829999 0.489999 90) (layer "F.SilkS")
        (effects (font (size 0.7 0.7) (thickness 0.15)) (justify left bottom))
    )
    (fp_text value "C_100n_0402" (at 0 1.4 90) (layer "F.Fab") hide
        (effects (font (size 0.7 0.7) (thickness 0.15)) (justify left bottom))
    )
    (fp_text user "Author: Antmicro" (at -0.932 4.17 90) (layer "F.Fab") hide
        (effects (font (size 0.7 0.7) (thickness 0.15)) (justify left bottom))
    )
    (fp_text user "${REFERENCE}" (at -0.932 3.168 90) (layer "F.Fab") hide
        (effects (font (size 0.7 0.7) (thickness 0.15)) (justify left bottom))
    )
    (fp_text user "License: Apache-2.0" (at -0.932 5.17 90) (layer "F.Fab") hide
        (effects (font (size 0.7 0.7) (thickness 0.15)) (justify left bottom))
    )
    (fp_rect (start -0.94 -0.47) (end 0.94 0.47)
      (stroke (width 0.05) (type solid)) (fill none) (layer "F.CrtYd"))
    (fp_rect (start -0.499 -0.249) (end 0.499 0.249)
      (stroke (width 0.15) (type solid)) (fill none) (layer "F.Fab"))
    (pad "1" smd roundrect (at -0.484 0 90) (size 0.59 0.64) (layers "F.Cu" "F.Paste" "F.Mask") (roundrect_rratio 0.25)
      (net 15 "PS_3V3") (pintype "passive"))
    (pad "2" smd roundrect (at 0.484 0 90) (size 0.59 0.64) (layers "F.Cu" "F.Paste" "F.Mask") (roundrect_rratio 0.25)
      (net 1 "GND") (pintype "passive"))
  )
	(footprint "kria-k26-devboard-footprints:TP_SMD_0.75mm" (layer "F.Cu")
    (at 100 137.3)
    (property "Author" "Antmicro")
    (property "License" "Apache-2.0")
    (property "MPN" "")
    (property "Manufacturer" "")
    (property "Sheetfile" "i2c.kicad_sch")
    (property "Sheetname" "I2C ")
    (property "ki_description" "Test Point 0.75mm")
    (attr exclude_from_pos_files)
    (fp_text reference "TP9" (at 0.41 2.32 90) (layer "F.SilkS")
        (effects (font (size 0.7 0.7) (thickness 0.15)) (justify left bottom))
    )
    (fp_text value "TP_0.75mm_SMD" (at 0 1.2) (layer "F.Fab") hide
        (effects (font (size 0.7 0.7) (thickness 0.15)) (justify left bottom))
    )
    (fp_text user "License: Apache-2.0" (at -0.4 5.101) (layer "F.Fab") hide
        (effects (font (size 0.7 0.7) (thickness 0.15)) (justify left bottom))
    )
    (fp_text user "${REFERENCE}" (at -0.4 2.7) (layer "F.Fab") hide
        (effects (font (size 0.7 0.7) (thickness 0.15)) (justify left bottom))
    )
    (fp_text user "Author: Antmicro" (at -0.4 3.901) (layer "F.Fab") hide
        (effects (font (size 0.7 0.7) (thickness 0.15)) (justify left bottom))
    )
    (pad "1" smd circle (at 0 0) (size 0.75 0.75) (layers "F.Cu" "F.Mask")
      (net 163 "/I2C /I2C_SDA_3V3") (pinfunction "1") (pintype "passive"))
  )
	(footprint "kria-k26-devboard-footprints:TP_SMD_0.75mm" (layer "F.Cu")
    (at 177.65 115)
    (property "Author" "Antmicro")
    (property "License" "Apache-2.0")
    (property "MPN" "")
    (property "Manufacturer" "")
    (property "Sheetfile" "dc-dc-conventers.kicad_sch")
    (property "Sheetname" "DC/DC conventers")
    (property "ki_description" "Test Point 0.75mm")
    (attr exclude_from_pos_files)
    (fp_text reference "TP38" (at -1.21 -1.67) (layer "F.SilkS")
        (effects (font (size 0.7 0.7) (thickness 0.15)) (justify left bottom))
    )
    (fp_text value "TP_0.75mm_SMD" (at 0 1.2) (layer "F.Fab") hide
        (effects (font (size 0.7 0.7) (thickness 0.15)) (justify left bottom))
    )
    (fp_text user "${REFERENCE}" (at -0.4 2.7) (layer "F.Fab") hide
        (effects (font (size 0.7 0.7) (thickness 0.15)) (justify left bottom))
    )
    (fp_text user "License: Apache-2.0" (at -0.4 5.101) (layer "F.Fab") hide
        (effects (font (size 0.7 0.7) (thickness 0.15)) (justify left bottom))
    )
    (fp_text user "Author: Antmicro" (at -0.4 3.901) (layer "F.Fab") hide
        (effects (font (size 0.7 0.7) (thickness 0.15)) (justify left bottom))
    )
    (pad "1" smd circle (at 0 0) (size 0.75 0.75) (layers "F.Cu" "F.Mask")
      (net 767 "/Power Supply/DC/DC conventers/PS_1V8_OUT") (pinfunction "1") (pintype "passive"))
  )
	(footprint "kria-k26-devboard-footprints:SOT-416" (layer "F.Cu")
    (at 184.04 135.75 -90)
    (descr "SOT-416")
    (tags "SOT-416")
    (property "Author" "Antmicro")
    (property "License" "Apache-2.0")
    (property "MPN" "DTC014TEBTL")
    (property "Manufacturer" "ROHM Semiconductor")
    (property "Sheetfile" "dc-dc-conventers.kicad_sch")
    (property "Sheetname" "DC/DC conventers")
    (property "ki_description" "Digital NPN Transistor, 10k/NONE, EMT-3")
    (attr smd)
    (fp_text reference "Q15" (at -0.89 -0.06 -90) (layer "F.SilkS")
        (effects (font (size 0.7 0.7) (thickness 0.15)) (justify left bottom))
    )
    (fp_text value "DTC014T_SOT-416" (at 0 2 -90) (layer "F.Fab") hide
        (effects (font (size 0.7 0.7) (thickness 0.15)) (justify left bottom))
    )
    (fp_text user "License: Apache-2.0" (at -1 5.802 -90) (layer "F.Fab") hide
        (effects (font (size 0.7 0.7) (thickness 0.15)) (justify left bottom))
    )
    (fp_text user "Author: Antmicro" (at -1 4.602 -90) (layer "F.Fab") hide
        (effects (font (size 0.7 0.7) (thickness 0.15)) (justify left bottom))
    )
    (fp_text user "${REFERENCE}" (at -1 3.4 -90) (layer "F.Fab") hide
        (effects (font (size 0.7 0.7) (thickness 0.15)) (justify left bottom))
    )
    (fp_line (start -0.5 -0.15) (end -0.5 0.15)
      (stroke (width 0.15) (type solid)) (layer "F.SilkS"))
    (fp_line (start 0.5 0.9) (end -0.5 0.9)
      (stroke (width 0.15) (type solid)) (layer "F.SilkS"))
    (fp_line (start 0.5 0.9) (end 0.5 0.7)
      (stroke (width 0.15) (type solid)) (layer "F.SilkS"))
    (fp_line (start 0.508 -0.9) (end -0.5 -0.9)
      (stroke (width 0.15) (type solid)) (layer "F.SilkS"))
    (fp_line (start 0.508 -0.9) (end 0.508 -0.592)
      (stroke (width 0.15) (type solid)) (layer "F.SilkS"))
    (fp_rect (start -1 -1.05) (end 1 1.05)
      (stroke (width 0.05) (type solid)) (fill none) (layer "F.CrtYd"))
    (fp_line (start -0.05 -0.9) (end -0.45 -0.5)
      (stroke (width 0.15) (type solid)) (layer "F.Fab"))
    (fp_rect (start 0.45 0.9) (end -0.45 -0.9)
      (stroke (width 0.15) (type solid)) (fill none) (layer "F.Fab"))
    (pad "1" smd rect (at -0.652 -0.5 270) (size 0.6 0.5) (layers "F.Cu" "F.Paste" "F.Mask")
      (net 771 "/Power Supply/DC/DC conventers/PL_1V2_OUT") (pinfunction "B") (pintype "input"))
    (pad "2" smd rect (at -0.652 0.498 270) (size 0.6 0.5) (layers "F.Cu" "F.Paste" "F.Mask")
      (net 1 "GND") (pinfunction "E") (pintype "passive"))
    (pad "3" smd rect (at 0.65 0 270) (size 0.6 0.5) (layers "F.Cu" "F.Paste" "F.Mask")
      (net 340 "Net-(Q15-C)") (pinfunction "C") (pintype "passive"))
  )
	(footprint "kria-k26-devboard-footprints:TP_SMD_0.75mm" (layer "F.Cu")
    (at 164.45 116.95)
    (property "Author" "Antmicro")
    (property "License" "Apache-2.0")
    (property "MPN" "")
    (property "Manufacturer" "")
    (property "Sheetfile" "dc-dc-conventers.kicad_sch")
    (property "Sheetname" "DC/DC conventers")
    (property "ki_description" "Test Point 0.75mm")
    (attr exclude_from_pos_files)
    (fp_text reference "TP39" (at -1.29 1.19 90) (layer "F.SilkS")
        (effects (font (size 0.7 0.7) (thickness 0.15)) (justify left bottom))
    )
    (fp_text value "TP_0.75mm_SMD" (at 0 1.2) (layer "F.Fab") hide
        (effects (font (size 0.7 0.7) (thickness 0.15)) (justify left bottom))
    )
    (fp_text user "${REFERENCE}" (at -0.4 2.7) (layer "F.Fab") hide
        (effects (font (size 0.7 0.7) (thickness 0.15)) (justify left bottom))
    )
    (fp_text user "Author: Antmicro" (at -0.4 3.901) (layer "F.Fab") hide
        (effects (font (size 0.7 0.7) (thickness 0.15)) (justify left bottom))
    )
    (fp_text user "License: Apache-2.0" (at -0.4 5.101) (layer "F.Fab") hide
        (effects (font (size 0.7 0.7) (thickness 0.15)) (justify left bottom))
    )
    (pad "1" smd circle (at 0 0) (size 0.75 0.75) (layers "F.Cu" "F.Mask")
      (net 768 "/Power Supply/DC/DC conventers/PS_1V2_OUT") (pinfunction "1") (pintype "passive"))
  )
)
